(kicad_pcb
	(version 20260206)
	(generator "pcbnew")
	(generator_version "10.0")
	(general
		(thickness 1.6)
		(legacy_teardrops no)
	)
	(paper "A4")
	(title_block
		(title "04192023_DAF0TMB3IC0_F0TG_MB_C_brd_V02_OCP.brd")
		(comment 1 "Grand Teton / footprints 8325-8331 of 8354")
	)
	(layers
		(0 "F.Cu" signal "TOP")
		(4 "In1.Cu" signal "GND")
		(6 "In2.Cu" signal "IN1")
		(8 "In3.Cu" signal "GND1")
		(10 "In4.Cu" signal "IN2")
		(12 "In5.Cu" signal "GND2")
		(14 "In6.Cu" signal "IN3")
		(16 "In7.Cu" signal "GND3")
		(18 "In8.Cu" signal "VCC")
		(20 "In9.Cu" signal "VCC1")
		(22 "In10.Cu" signal "GND4")
		(24 "In11.Cu" signal "IN4")
		(26 "In12.Cu" signal "GND5")
		(28 "In13.Cu" signal "IN5")
		(30 "In14.Cu" signal "GND6")
		(32 "In15.Cu" signal "IN6")
		(34 "In16.Cu" signal "GND7")
		(2 "B.Cu" signal "BOTTOM")
		(9 "F.Adhes" user "F.Adhesive")
		(11 "B.Adhes" user "B.Adhesive")
		(13 "F.Paste" user "Package Geometry/Pastemask Top")
		(15 "B.Paste" user "Package Geometry/Pastemask Bottom")
		(5 "F.SilkS" user "Ref Des/Silkscreen Top")
		(7 "B.SilkS" user "Ref Des/Silkscreen Bottom")
		(1 "F.Mask" user "Board Geometry/Soldermask Top")
		(3 "B.Mask" user "Board Geometry/Soldermask Bottom")
		(17 "Dwgs.User" user "User.Drawings")
		(19 "Cmts.User" user "User.Comments")
		(21 "Eco1.User" user "User.Eco1")
		(23 "Eco2.User" user "User.Eco2")
		(25 "Edge.Cuts" user "Board Geometry/Outline")
		(27 "Margin" user)
		(31 "F.CrtYd" user "Package Geometry/Place Bound Top")
		(29 "B.CrtYd" user "Package Geometry/Place Bound Bottom")
		(35 "F.Fab" user "Ref Des/Assembly Top")
		(33 "B.Fab" user "Ref Des/Assembly Bottom")
	)
	(footprint ""
		(layer "B.Cu")
		(at 234.843828 -324.793102 180)
		(property "Reference" "R1220"
			(at 0 0 0)
			(layer "B.SilkS")
			(hide yes)
			(effects
				(font
					(size 1.27 1.27)
				)
				(justify mirror)
			)
		)
		(property "Value" ""
			(at 0 0 0)
			(layer "B.Fab")
			(effects
				(font
					(size 1.27 1.27)
				)
				(justify mirror)
			)
		)
		(duplicate_pad_numbers_are_jumpers no)
		(fp_line
			(start 0.7874 0.4064)
			(end 0.7874 -0.4064)
			(stroke
				(width 0.1524)
				(type default)
			)
			(layer "B.SilkS")
		)
		(fp_line
			(start 0.7874 -0.4064)
			(end -0.7874 -0.4064)
			(stroke
				(width 0.1524)
				(type default)
			)
			(layer "B.SilkS")
		)
		(fp_line
			(start -0.7874 0.4064)
			(end 0.7874 0.4064)
			(stroke
				(width 0.1524)
				(type default)
			)
			(layer "B.SilkS")
		)
		(fp_line
			(start -0.7874 -0.4064)
			(end -0.7874 0.4064)
			(stroke
				(width 0.1524)
				(type default)
			)
			(layer "B.SilkS")
		)
		(fp_line
			(start 0.67945 0.3048)
			(end 0.67945 -0.305054)
			(stroke
				(width 0.1)
				(type default)
			)
			(layer "B.Fab")
		)
		(fp_line
			(start 0.67945 -0.305054)
			(end 0.12065 -0.305054)
			(stroke
				(width 0.1)
				(type default)
			)
			(layer "B.Fab")
		)
		(fp_line
			(start 0.12065 0.3048)
			(end 0.67945 0.3048)
			(stroke
				(width 0.1)
				(type default)
			)
			(layer "B.Fab")
		)
		(fp_line
			(start 0.12065 0.2794)
			(end 0.12065 0.3048)
			(stroke
				(width 0.1)
				(type default)
			)
			(layer "B.Fab")
		)
		(fp_line
			(start 0.12065 -0.2794)
			(end -0.12065 -0.2794)
			(stroke
				(width 0.1)
				(type default)
			)
			(layer "B.Fab")
		)
		(fp_line
			(start 0.12065 -0.305054)
			(end 0.12065 -0.2794)
			(stroke
				(width 0.1)
				(type default)
			)
			(layer "B.Fab")
		)
		(fp_line
			(start -0.120396 0.3048)
			(end -0.120396 0.2794)
			(stroke
				(width 0.1)
				(type default)
			)
			(layer "B.Fab")
		)
		(fp_line
			(start -0.120396 0.2794)
			(end 0.12065 0.2794)
			(stroke
				(width 0.1)
				(type default)
			)
			(layer "B.Fab")
		)
		(fp_line
			(start -0.12065 -0.2794)
			(end -0.12065 -0.3048)
			(stroke
				(width 0.1)
				(type default)
			)
			(layer "B.Fab")
		)
		(fp_line
			(start -0.12065 -0.3048)
			(end -0.67945 -0.3048)
			(stroke
				(width 0.1)
				(type default)
			)
			(layer "B.Fab")
		)
		(fp_line
			(start -0.67945 0.3048)
			(end -0.120396 0.3048)
			(stroke
				(width 0.1)
				(type default)
			)
			(layer "B.Fab")
		)
		(fp_line
			(start -0.67945 -0.3048)
			(end -0.67945 0.3048)
			(stroke
				(width 0.1)
				(type default)
			)
			(layer "B.Fab")
		)
		(pad "1" smd circle
			(at 0.40005 0)
			(size 0 0)
			(layers "B.Cu" "B.Mask" "B.Paste")
			(net "P1V8_CPU0_RT_1D_ADC")
		)
		(pad "2" smd circle
			(at -0.40005 0)
			(size 0 0)
			(layers "B.Cu" "B.Mask" "B.Paste")
			(net "GND")
		)
	)
	(footprint ""
		(layer "B.Cu")
		(at 79.225648 -182.656734 -90)
		(property "Reference" "PC268_1"
			(at 0 0 90)
			(layer "B.SilkS")
			(hide yes)
			(effects
				(font
					(size 1.27 1.27)
				)
				(justify mirror)
			)
		)
		(property "Value" ""
			(at 0 0 90)
			(layer "B.Fab")
			(effects
				(font
					(size 1.27 1.27)
				)
				(justify mirror)
			)
		)
		(duplicate_pad_numbers_are_jumpers no)
		(fp_line
			(start -1.524 0.762)
			(end 1.524 0.762)
			(stroke
				(width 0.1524)
				(type default)
			)
			(layer "B.SilkS")
		)
		(fp_line
			(start 1.524 0.762)
			(end 1.524 -0.762)
			(stroke
				(width 0.1524)
				(type default)
			)
			(layer "B.SilkS")
		)
		(fp_line
			(start -1.524 -0.762)
			(end -1.524 0.762)
			(stroke
				(width 0.1524)
				(type default)
			)
			(layer "B.SilkS")
		)
		(fp_line
			(start 1.524 -0.762)
			(end -1.524 -0.762)
			(stroke
				(width 0.1524)
				(type default)
			)
			(layer "B.SilkS")
		)
		(fp_line
			(start -1.1049 0.724916)
			(end -1.1049 -0.724916)
			(stroke
				(width 0.1)
				(type default)
			)
			(layer "B.Fab")
		)
		(fp_line
			(start 1.1049 0.724916)
			(end -1.1049 0.724916)
			(stroke
				(width 0.1)
				(type default)
			)
			(layer "B.Fab")
		)
		(fp_line
			(start -1.1049 -0.724916)
			(end 1.1049 -0.724916)
			(stroke
				(width 0.1)
				(type default)
			)
			(layer "B.Fab")
		)
		(fp_line
			(start 1.1049 -0.724916)
			(end 1.1049 0.724916)
			(stroke
				(width 0.1)
				(type default)
			)
			(layer "B.Fab")
		)
		(pad "1" smd rect
			(at 0.889 0 270)
			(size 1.016 1.27)
			(layers "B.Cu" "B.Mask" "B.Paste")
			(net "SW_P12V_AUX_PVDDCR_CPU0_P1_FLT")
		)
		(pad "2" smd rect
			(at -0.889 0 270)
			(size 1.016 1.27)
			(layers "B.Cu" "B.Mask" "B.Paste")
			(net "GND")
		)
	)
	(footprint ""
		(layer "B.Cu")
		(at 52.74564 -424.225212 -90)
		(property "Reference" "R2935"
			(at 0 0 90)
			(layer "B.SilkS")
			(hide yes)
			(effects
				(font
					(size 1.27 1.27)
				)
				(justify mirror)
			)
		)
		(property "Value" ""
			(at 0 0 90)
			(layer "B.Fab")
			(effects
				(font
					(size 1.27 1.27)
				)
				(justify mirror)
			)
		)
		(duplicate_pad_numbers_are_jumpers no)
		(fp_line
			(start -0.7874 0.4064)
			(end 0.7874 0.4064)
			(stroke
				(width 0.1524)
				(type default)
			)
			(layer "B.SilkS")
		)
		(fp_line
			(start 0.7874 0.4064)
			(end 0.7874 -0.4064)
			(stroke
				(width 0.1524)
				(type default)
			)
			(layer "B.SilkS")
		)
		(fp_line
			(start -0.7874 -0.4064)
			(end -0.7874 0.4064)
			(stroke
				(width 0.1524)
				(type default)
			)
			(layer "B.SilkS")
		)
		(fp_line
			(start 0.7874 -0.4064)
			(end -0.7874 -0.4064)
			(stroke
				(width 0.1524)
				(type default)
			)
			(layer "B.SilkS")
		)
		(fp_line
			(start -0.67945 0.3048)
			(end -0.120396 0.3048)
			(stroke
				(width 0.1)
				(type default)
			)
			(layer "B.Fab")
		)
		(fp_line
			(start -0.120396 0.3048)
			(end -0.120396 0.2794)
			(stroke
				(width 0.1)
				(type default)
			)
			(layer "B.Fab")
		)
		(fp_line
			(start 0.12065 0.3048)
			(end 0.67945 0.3048)
			(stroke
				(width 0.1)
				(type default)
			)
			(layer "B.Fab")
		)
		(fp_line
			(start 0.67945 0.3048)
			(end 0.67945 -0.305054)
			(stroke
				(width 0.1)
				(type default)
			)
			(layer "B.Fab")
		)
		(fp_line
			(start -0.120396 0.2794)
			(end 0.12065 0.2794)
			(stroke
				(width 0.1)
				(type default)
			)
			(layer "B.Fab")
		)
		(fp_line
			(start 0.12065 0.2794)
			(end 0.12065 0.3048)
			(stroke
				(width 0.1)
				(type default)
			)
			(layer "B.Fab")
		)
		(fp_line
			(start -0.12065 -0.2794)
			(end -0.12065 -0.3048)
			(stroke
				(width 0.1)
				(type default)
			)
			(layer "B.Fab")
		)
		(fp_line
			(start 0.12065 -0.2794)
			(end -0.12065 -0.2794)
			(stroke
				(width 0.1)
				(type default)
			)
			(layer "B.Fab")
		)
		(fp_line
			(start -0.67945 -0.3048)
			(end -0.67945 0.3048)
			(stroke
				(width 0.1)
				(type default)
			)
			(layer "B.Fab")
		)
		(fp_line
			(start -0.12065 -0.3048)
			(end -0.67945 -0.3048)
			(stroke
				(width 0.1)
				(type default)
			)
			(layer "B.Fab")
		)
		(fp_line
			(start 0.12065 -0.305054)
			(end 0.12065 -0.2794)
			(stroke
				(width 0.1)
				(type default)
			)
			(layer "B.Fab")
		)
		(fp_line
			(start 0.67945 -0.305054)
			(end 0.12065 -0.305054)
			(stroke
				(width 0.1)
				(type default)
			)
			(layer "B.Fab")
		)
		(pad "1" smd circle
			(at 0.40005 0 90)
			(size 0 0)
			(layers "B.Cu" "B.Mask" "B.Paste")
			(net "P3V3_AUX")
		)
		(pad "2" smd circle
			(at -0.40005 0 90)
			(size 0 0)
			(layers "B.Cu" "B.Mask" "B.Paste")
			(net "FM_GPU_PWRGD_ISO")
		)
	)
	(footprint ""
		(layer "B.Cu")
		(at 142.2908 -13.763752 90)
		(property "Reference" "R6032"
			(at 0 0 90)
			(layer "B.SilkS")
			(hide yes)
			(effects
				(font
					(size 1.27 1.27)
				)
				(justify mirror)
			)
		)
		(property "Value" ""
			(at 0 0 90)
			(layer "B.Fab")
			(effects
				(font
					(size 1.27 1.27)
				)
				(justify mirror)
			)
		)
		(duplicate_pad_numbers_are_jumpers no)
		(fp_line
			(start 0.7874 -0.4064)
			(end -0.7874 -0.4064)
			(stroke
				(width 0.1524)
				(type default)
			)
			(layer "B.SilkS")
		)
		(fp_line
			(start -0.7874 -0.4064)
			(end -0.7874 0.4064)
			(stroke
				(width 0.1524)
				(type default)
			)
			(layer "B.SilkS")
		)
		(fp_line
			(start 0.7874 0.4064)
			(end 0.7874 -0.4064)
			(stroke
				(width 0.1524)
				(type default)
			)
			(layer "B.SilkS")
		)
		(fp_line
			(start -0.7874 0.4064)
			(end 0.7874 0.4064)
			(stroke
				(width 0.1524)
				(type default)
			)
			(layer "B.SilkS")
		)
		(fp_line
			(start 0.67945 -0.305054)
			(end 0.12065 -0.305054)
			(stroke
				(width 0.1)
				(type default)
			)
			(layer "B.Fab")
		)
		(fp_line
			(start 0.12065 -0.305054)
			(end 0.12065 -0.2794)
			(stroke
				(width 0.1)
				(type default)
			)
			(layer "B.Fab")
		)
		(fp_line
			(start -0.12065 -0.3048)
			(end -0.67945 -0.3048)
			(stroke
				(width 0.1)
				(type default)
			)
			(layer "B.Fab")
		)
		(fp_line
			(start -0.67945 -0.3048)
			(end -0.67945 0.3048)
			(stroke
				(width 0.1)
				(type default)
			)
			(layer "B.Fab")
		)
		(fp_line
			(start 0.12065 -0.2794)
			(end -0.12065 -0.2794)
			(stroke
				(width 0.1)
				(type default)
			)
			(layer "B.Fab")
		)
		(fp_line
			(start -0.12065 -0.2794)
			(end -0.12065 -0.3048)
			(stroke
				(width 0.1)
				(type default)
			)
			(layer "B.Fab")
		)
		(fp_line
			(start 0.12065 0.2794)
			(end 0.12065 0.3048)
			(stroke
				(width 0.1)
				(type default)
			)
			(layer "B.Fab")
		)
		(fp_line
			(start -0.120396 0.2794)
			(end 0.12065 0.2794)
			(stroke
				(width 0.1)
				(type default)
			)
			(layer "B.Fab")
		)
		(fp_line
			(start 0.67945 0.3048)
			(end 0.67945 -0.305054)
			(stroke
				(width 0.1)
				(type default)
			)
			(layer "B.Fab")
		)
		(fp_line
			(start 0.12065 0.3048)
			(end 0.67945 0.3048)
			(stroke
				(width 0.1)
				(type default)
			)
			(layer "B.Fab")
		)
		(fp_line
			(start -0.120396 0.3048)
			(end -0.120396 0.2794)
			(stroke
				(width 0.1)
				(type default)
			)
			(layer "B.Fab")
		)
		(fp_line
			(start -0.67945 0.3048)
			(end -0.120396 0.3048)
			(stroke
				(width 0.1)
				(type default)
			)
			(layer "B.Fab")
		)
		(pad "1" smd circle
			(at 0.40005 0 270)
			(size 0 0)
			(layers "B.Cu" "B.Mask" "B.Paste")
			(net "JTAG_SCM_DBREQ_N")
		)
		(pad "2" smd circle
			(at -0.40005 0 270)
			(size 0 0)
			(layers "B.Cu" "B.Mask" "B.Paste")
			(net "SCM_HDT_DBREQ_N")
		)
	)
	(footprint ""
		(layer "B.Cu")
		(at 122.745754 -161.411412 90)
		(property "Reference" "PC328_2"
			(at 0 0 90)
			(layer "B.SilkS")
			(hide yes)
			(effects
				(font
					(size 1.27 1.27)
				)
				(justify mirror)
			)
		)
		(property "Value" ""
			(at 0 0 90)
			(layer "B.Fab")
			(effects
				(font
					(size 1.27 1.27)
				)
				(justify mirror)
			)
		)
		(duplicate_pad_numbers_are_jumpers no)
		(fp_line
			(start 1.524 -0.762)
			(end -1.524 -0.762)
			(stroke
				(width 0.1524)
				(type default)
			)
			(layer "B.SilkS")
		)
		(fp_line
			(start -1.524 -0.762)
			(end -1.524 0.762)
			(stroke
				(width 0.1524)
				(type default)
			)
			(layer "B.SilkS")
		)
		(fp_line
			(start 1.524 0.762)
			(end 1.524 -0.762)
			(stroke
				(width 0.1524)
				(type default)
			)
			(layer "B.SilkS")
		)
		(fp_line
			(start -1.524 0.762)
			(end 1.524 0.762)
			(stroke
				(width 0.1524)
				(type default)
			)
			(layer "B.SilkS")
		)
		(fp_line
			(start 1.1049 -0.724916)
			(end 1.1049 0.724916)
			(stroke
				(width 0.1)
				(type default)
			)
			(layer "B.Fab")
		)
		(fp_line
			(start -1.1049 -0.724916)
			(end 1.1049 -0.724916)
			(stroke
				(width 0.1)
				(type default)
			)
			(layer "B.Fab")
		)
		(fp_line
			(start 1.1049 0.724916)
			(end -1.1049 0.724916)
			(stroke
				(width 0.1)
				(type default)
			)
			(layer "B.Fab")
		)
		(fp_line
			(start -1.1049 0.724916)
			(end -1.1049 -0.724916)
			(stroke
				(width 0.1)
				(type default)
			)
			(layer "B.Fab")
		)
		(pad "1" smd rect
			(at 0.889 0 90)
			(size 1.016 1.27)
			(layers "B.Cu" "B.Mask" "B.Paste")
			(net "SW_P12V_AUX_PVDDCR_SOC_P1_FLT")
		)
		(pad "2" smd rect
			(at -0.889 0 90)
			(size 1.016 1.27)
			(layers "B.Cu" "B.Mask" "B.Paste")
			(net "GND")
		)
	)
	(footprint ""
		(layer "B.Cu")
		(at 197.523608 -104.481376)
		(property "Reference" "R230"
			(at 0 0 0)
			(layer "B.SilkS")
			(hide yes)
			(effects
				(font
					(size 1.27 1.27)
				)
				(justify mirror)
			)
		)
		(property "Value" ""
			(at 0 0 0)
			(layer "B.Fab")
			(effects
				(font
					(size 1.27 1.27)
				)
				(justify mirror)
			)
		)
		(duplicate_pad_numbers_are_jumpers no)
		(fp_line
			(start -0.7874 -0.4064)
			(end -0.7874 0.4064)
			(stroke
				(width 0.1524)
				(type default)
			)
			(layer "B.SilkS")
		)
		(fp_line
			(start -0.7874 0.4064)
			(end 0.7874 0.4064)
			(stroke
				(width 0.1524)
				(type default)
			)
			(layer "B.SilkS")
		)
		(fp_line
			(start 0.7874 -0.4064)
			(end -0.7874 -0.4064)
			(stroke
				(width 0.1524)
				(type default)
			)
			(layer "B.SilkS")
		)
		(fp_line
			(start 0.7874 0.4064)
			(end 0.7874 -0.4064)
			(stroke
				(width 0.1524)
				(type default)
			)
			(layer "B.SilkS")
		)
		(fp_line
			(start -0.67945 -0.3048)
			(end -0.67945 0.3048)
			(stroke
				(width 0.1)
				(type default)
			)
			(layer "B.Fab")
		)
		(fp_line
			(start -0.67945 0.3048)
			(end -0.120396 0.3048)
			(stroke
				(width 0.1)
				(type default)
			)
			(layer "B.Fab")
		)
		(fp_line
			(start -0.12065 -0.3048)
			(end -0.67945 -0.3048)
			(stroke
				(width 0.1)
				(type default)
			)
			(layer "B.Fab")
		)
		(fp_line
			(start -0.12065 -0.2794)
			(end -0.12065 -0.3048)
			(stroke
				(width 0.1)
				(type default)
			)
			(layer "B.Fab")
		)
		(fp_line
			(start -0.120396 0.2794)
			(end 0.12065 0.2794)
			(stroke
				(width 0.1)
				(type default)
			)
			(layer "B.Fab")
		)
		(fp_line
			(start -0.120396 0.3048)
			(end -0.120396 0.2794)
			(stroke
				(width 0.1)
				(type default)
			)
			(layer "B.Fab")
		)
		(fp_line
			(start 0.12065 -0.305054)
			(end 0.12065 -0.2794)
			(stroke
				(width 0.1)
				(type default)
			)
			(layer "B.Fab")
		)
		(fp_line
			(start 0.12065 -0.2794)
			(end -0.12065 -0.2794)
			(stroke
				(width 0.1)
				(type default)
			)
			(layer "B.Fab")
		)
		(fp_line
			(start 0.12065 0.2794)
			(end 0.12065 0.3048)
			(stroke
				(width 0.1)
				(type default)
			)
			(layer "B.Fab")
		)
		(fp_line
			(start 0.12065 0.3048)
			(end 0.67945 0.3048)
			(stroke
				(width 0.1)
				(type default)
			)
			(layer "B.Fab")
		)
		(fp_line
			(start 0.67945 -0.305054)
			(end 0.12065 -0.305054)
			(stroke
				(width 0.1)
				(type default)
			)
			(layer "B.Fab")
		)
		(fp_line
			(start 0.67945 0.3048)
			(end 0.67945 -0.305054)
			(stroke
				(width 0.1)
				(type default)
			)
			(layer "B.Fab")
		)
		(pad "1" smd circle
			(at 0.40005 0 180)
			(size 0 0)
			(layers "B.Cu" "B.Mask" "B.Paste")
			(net "PWRGD_PVDDIO_P0")
		)
		(pad "2" smd circle
			(at -0.40005 0 180)
			(size 0 0)
			(layers "B.Cu" "B.Mask" "B.Paste")
			(net "FM_PWRGD_PVDDIO_P0")
		)
	)
	(footprint ""
		(layer "B.Cu")
		(at 101.385878 -143.61541 180)
		(property "Reference" "PC250"
			(at 0 0 0)
			(layer "B.SilkS")
			(hide yes)
			(effects
				(font
					(size 1.27 1.27)
				)
				(justify mirror)
			)
		)
		(property "Value" ""
			(at 0 0 0)
			(layer "B.Fab")
			(effects
				(font
					(size 1.27 1.27)
				)
				(justify mirror)
			)
		)
		(duplicate_pad_numbers_are_jumpers no)
		(fp_line
			(start 0.7874 0.4064)
			(end 0.7874 -0.4064)
			(stroke
				(width 0.1524)
				(type default)
			)
			(layer "B.SilkS")
		)
		(fp_line
			(start 0.7874 -0.4064)
			(end -0.7874 -0.4064)
			(stroke
				(width 0.1524)
				(type default)
			)
			(layer "B.SilkS")
		)
		(fp_line
			(start -0.7874 0.4064)
			(end 0.7874 0.4064)
			(stroke
				(width 0.1524)
				(type default)
			)
			(layer "B.SilkS")
		)
		(fp_line
			(start -0.7874 -0.4064)
			(end -0.7874 0.4064)
			(stroke
				(width 0.1524)
				(type default)
			)
			(layer "B.SilkS")
		)
		(fp_line
			(start 0.67945 0.3048)
			(end 0.67945 -0.305054)
			(stroke
				(width 0.1)
				(type default)
			)
			(layer "B.Fab")
		)
		(fp_line
			(start 0.67945 -0.305054)
			(end 0.12065 -0.305054)
			(stroke
				(width 0.1)
				(type default)
			)
			(layer "B.Fab")
		)
		(fp_line
			(start 0.12065 0.3048)
			(end 0.67945 0.3048)
			(stroke
				(width 0.1)
				(type default)
			)
			(layer "B.Fab")
		)
		(fp_line
			(start 0.12065 0.2794)
			(end 0.12065 0.3048)
			(stroke
				(width 0.1)
				(type default)
			)
			(layer "B.Fab")
		)
		(fp_line
			(start 0.12065 -0.2794)
			(end -0.12065 -0.2794)
			(stroke
				(width 0.1)
				(type default)
			)
			(layer "B.Fab")
		)
		(fp_line
			(start 0.12065 -0.305054)
			(end 0.12065 -0.2794)
			(stroke
				(width 0.1)
				(type default)
			)
			(layer "B.Fab")
		)
		(fp_line
			(start -0.120396 0.3048)
			(end -0.120396 0.2794)
			(stroke
				(width 0.1)
				(type default)
			)
			(layer "B.Fab")
		)
		(fp_line
			(start -0.120396 0.2794)
			(end 0.12065 0.2794)
			(stroke
				(width 0.1)
				(type default)
			)
			(layer "B.Fab")
		)
		(fp_line
			(start -0.12065 -0.2794)
			(end -0.12065 -0.3048)
			(stroke
				(width 0.1)
				(type default)
			)
			(layer "B.Fab")
		)
		(fp_line
			(start -0.12065 -0.3048)
			(end -0.67945 -0.3048)
			(stroke
				(width 0.1)
				(type default)
			)
			(layer "B.Fab")
		)
		(fp_line
			(start -0.67945 0.3048)
			(end -0.120396 0.3048)
			(stroke
				(width 0.1)
				(type default)
			)
			(layer "B.Fab")
		)
		(fp_line
			(start -0.67945 -0.3048)
			(end -0.67945 0.3048)
			(stroke
				(width 0.1)
				(type default)
			)
			(layer "B.Fab")
		)
		(pad "1" smd circle
			(at 0.40005 0)
			(size 0 0)
			(layers "B.Cu" "B.Mask" "B.Paste")
			(net "PVDDCR_CPU0_P1_TEMP0")
		)
		(pad "2" smd circle
			(at -0.40005 0)
			(size 0 0)
			(layers "B.Cu" "B.Mask" "B.Paste")
			(net "GND")
		)
	)
)
